# S9S_MB_2U (Grand Teton) — schematic netlist excerpt (pin names and nets, part order shuffled) for the footprints in the layout excerpt that follows; sources: Cadence DE-HDL packaged netlist, KiCad conversion of 03242023_DA0F0TMBIJ0_F0T_Motherboard_J_brd_V01_OCP.brd

C1004  Q_CAP  10UF 6.3V 20% X6S  pkg C0402  page 74 : A = PVCCIN_CPU0 ; B = GND
R2365  Q_RES  1K 1% CHIP  pkg 0402LF  page 266 : A = P3V3_AUX ; B = PWRGD_PVCCIN_CPU0_R

(kicad_pcb
	(version 20260206)
	(generator "pcbnew")
	(generator_version "10.0")
	(general
		(thickness 1.6)
		(legacy_teardrops no)
	)
	(paper "A4")
	(title_block
		(title "03242023_DA0F0TMBIJ0_F0T_Motherboard_J_brd_V01_OCP.brd")
		(comment 1 "Grand Teton / footprints 2206-2207 of 6105")
	)
	(layers
		(0 "F.Cu" signal "TOP")
		(4 "In1.Cu" signal "GND")
		(6 "In2.Cu" signal "IN1")
		(8 "In3.Cu" signal "GND1")
		(10 "In4.Cu" signal "IN2")
		(12 "In5.Cu" signal "GND2")
		(14 "In6.Cu" signal "IN3")
		(16 "In7.Cu" signal "GND3")
		(18 "In8.Cu" signal "VCC")
		(20 "In9.Cu" signal "VCC1")
		(22 "In10.Cu" signal "GND4")
		(24 "In11.Cu" signal "IN4")
		(26 "In12.Cu" signal "GND5")
		(28 "In13.Cu" signal "IN5")
		(30 "In14.Cu" signal "GND6")
		(32 "In15.Cu" signal "IN6")
		(34 "In16.Cu" signal "GND7")
		(2 "B.Cu" signal "BOTTOM")
		(9 "F.Adhes" user "F.Adhesive")
		(11 "B.Adhes" user "B.Adhesive")
		(13 "F.Paste" user "Package Geometry/Pastemask Top")
		(15 "B.Paste" user "Package Geometry/Pastemask Bottom")
		(5 "F.SilkS" user "Ref Des/Silkscreen Top")
		(7 "B.SilkS" user "Ref Des/Silkscreen Bottom")
		(1 "F.Mask" user "Board Geometry/Soldermask Top")
		(3 "B.Mask" user "Board Geometry/Soldermask Bottom")
		(17 "Dwgs.User" user "User.Drawings")
		(19 "Cmts.User" user "User.Comments")
		(21 "Eco1.User" user "User.Eco1")
		(23 "Eco2.User" user "User.Eco2")
		(25 "Edge.Cuts" user "Board Geometry/Outline")
		(27 "Margin" user)
		(31 "F.CrtYd" user "Package Geometry/Place Bound Top")
		(29 "B.CrtYd" user "Package Geometry/Place Bound Bottom")
		(35 "F.Fab" user "Ref Des/Assembly Top")
		(33 "B.Fab" user "Ref Des/Assembly Bottom")
	)
	(footprint ""
		(layer "F.Cu")
		(at 350.790764 -360.934762 -90)
		(property "Reference" "R2365"
			(at 0 0 270)
			(layer "F.SilkS")
			(hide yes)
			(effects
				(font
					(size 1.27 1.27)
				)
			)
		)
		(property "Value" ""
			(at 0 0 270)
			(layer "F.Fab")
			(effects
				(font
					(size 1.27 1.27)
				)
			)
		)
		(duplicate_pad_numbers_are_jumpers no)
		(fp_line
			(start -0.7874 0.4064)
			(end -0.7874 -0.4064)
			(stroke
				(width 0.1524)
				(type default)
			)
			(layer "F.SilkS")
		)
		(fp_line
			(start 0.7874 0.4064)
			(end -0.7874 0.4064)
			(stroke
				(width 0.1524)
				(type default)
			)
			(layer "F.SilkS")
		)
		(fp_line
			(start -0.7874 -0.4064)
			(end 0.7874 -0.4064)
			(stroke
				(width 0.1524)
				(type default)
			)
			(layer "F.SilkS")
		)
		(fp_line
			(start 0.7874 -0.4064)
			(end 0.7874 0.4064)
			(stroke
				(width 0.1524)
				(type default)
			)
			(layer "F.SilkS")
		)
		(fp_line
			(start -0.67945 0.3048)
			(end -0.67945 -0.305054)
			(stroke
				(width 0.1)
				(type default)
			)
			(layer "F.Fab")
		)
		(fp_line
			(start -0.12065 0.3048)
			(end -0.67945 0.3048)
			(stroke
				(width 0.1)
				(type default)
			)
			(layer "F.Fab")
		)
		(fp_line
			(start 0.120396 0.3048)
			(end 0.120396 0.2794)
			(stroke
				(width 0.1)
				(type default)
			)
			(layer "F.Fab")
		)
		(fp_line
			(start 0.67945 0.3048)
			(end 0.120396 0.3048)
			(stroke
				(width 0.1)
				(type default)
			)
			(layer "F.Fab")
		)
		(fp_line
			(start -0.12065 0.2794)
			(end -0.12065 0.3048)
			(stroke
				(width 0.1)
				(type default)
			)
			(layer "F.Fab")
		)
		(fp_line
			(start 0.120396 0.2794)
			(end -0.12065 0.2794)
			(stroke
				(width 0.1)
				(type default)
			)
			(layer "F.Fab")
		)
		(fp_line
			(start -0.12065 -0.2794)
			(end 0.12065 -0.2794)
			(stroke
				(width 0.1)
				(type default)
			)
			(layer "F.Fab")
		)
		(fp_line
			(start 0.12065 -0.2794)
			(end 0.12065 -0.3048)
			(stroke
				(width 0.1)
				(type default)
			)
			(layer "F.Fab")
		)
		(fp_line
			(start 0.12065 -0.3048)
			(end 0.67945 -0.3048)
			(stroke
				(width 0.1)
				(type default)
			)
			(layer "F.Fab")
		)
		(fp_line
			(start 0.67945 -0.3048)
			(end 0.67945 0.3048)
			(stroke
				(width 0.1)
				(type default)
			)
			(layer "F.Fab")
		)
		(fp_line
			(start -0.67945 -0.305054)
			(end -0.12065 -0.305054)
			(stroke
				(width 0.1)
				(type default)
			)
			(layer "F.Fab")
		)
		(fp_line
			(start -0.12065 -0.305054)
			(end -0.12065 -0.2794)
			(stroke
				(width 0.1)
				(type default)
			)
			(layer "F.Fab")
		)
		(pad "1" smd circle
			(at -0.40005 0 270)
			(size 0 0)
			(layers "F.Cu" "F.Mask" "F.Paste")
			(net "P3V3_AUX")
		)
		(pad "2" smd circle
			(at 0.40005 0 270)
			(size 0 0)
			(layers "F.Cu" "F.Mask" "F.Paste")
			(net "PWRGD_PVCCIN_CPU0_R")
		)
	)
	(footprint ""
		(layer "F.Cu")
		(at 365.46663 -255.053846 90)
		(property "Reference" "C1004"
			(at 0 0 90)
			(layer "F.SilkS")
			(hide yes)
			(effects
				(font
					(size 1.27 1.27)
				)
			)
		)
		(property "Value" ""
			(at 0 0 90)
			(layer "F.Fab")
			(effects
				(font
					(size 1.27 1.27)
				)
			)
		)
		(duplicate_pad_numbers_are_jumpers no)
		(fp_line
			(start 0.7874 -0.4064)
			(end 0.7874 0.4064)
			(stroke
				(width 0.1524)
				(type default)
			)
			(layer "F.SilkS")
		)
		(fp_line
			(start -0.7874 -0.4064)
			(end 0.7874 -0.4064)
			(stroke
				(width 0.1524)
				(type default)
			)
			(layer "F.SilkS")
		)
		(fp_line
			(start 0.7874 0.4064)
			(end -0.7874 0.4064)
			(stroke
				(width 0.1524)
				(type default)
			)
			(layer "F.SilkS")
		)
		(fp_line
			(start -0.7874 0.4064)
			(end -0.7874 -0.4064)
			(stroke
				(width 0.1524)
				(type default)
			)
			(layer "F.SilkS")
		)
		(fp_line
			(start -0.12065 -0.305054)
			(end -0.12065 -0.2794)
			(stroke
				(width 0.1)
				(type default)
			)
			(layer "F.Fab")
		)
		(fp_line
			(start -0.67945 -0.305054)
			(end -0.12065 -0.305054)
			(stroke
				(width 0.1)
				(type default)
			)
			(layer "F.Fab")
		)
		(fp_line
			(start 0.67945 -0.3048)
			(end 0.67945 0.3048)
			(stroke
				(width 0.1)
				(type default)
			)
			(layer "F.Fab")
		)
		(fp_line
			(start 0.12065 -0.3048)
			(end 0.67945 -0.3048)
			(stroke
				(width 0.1)
				(type default)
			)
			(layer "F.Fab")
		)
		(fp_line
			(start 0.12065 -0.2794)
			(end 0.12065 -0.3048)
			(stroke
				(width 0.1)
				(type default)
			)
			(layer "F.Fab")
		)
		(fp_line
			(start -0.12065 -0.2794)
			(end 0.12065 -0.2794)
			(stroke
				(width 0.1)
				(type default)
			)
			(layer "F.Fab")
		)
		(fp_line
			(start 0.120396 0.2794)
			(end -0.12065 0.2794)
			(stroke
				(width 0.1)
				(type default)
			)
			(layer "F.Fab")
		)
		(fp_line
			(start -0.12065 0.2794)
			(end -0.12065 0.3048)
			(stroke
				(width 0.1)
				(type default)
			)
			(layer "F.Fab")
		)
		(fp_line
			(start 0.67945 0.3048)
			(end 0.120396 0.3048)
			(stroke
				(width 0.1)
				(type default)
			)
			(layer "F.Fab")
		)
		(fp_line
			(start 0.120396 0.3048)
			(end 0.120396 0.2794)
			(stroke
				(width 0.1)
				(type default)
			)
			(layer "F.Fab")
		)
		(fp_line
			(start -0.12065 0.3048)
			(end -0.67945 0.3048)
			(stroke
				(width 0.1)
				(type default)
			)
			(layer "F.Fab")
		)
		(fp_line
			(start -0.67945 0.3048)
			(end -0.67945 -0.305054)
			(stroke
				(width 0.1)
				(type default)
			)
			(layer "F.Fab")
		)
		(pad "1" smd circle
			(at -0.40005 0 90)
			(size 0 0)
			(layers "F.Cu" "F.Mask" "F.Paste")
			(net "PVCCIN_CPU0")
		)
		(pad "2" smd circle
			(at 0.40005 0 90)
			(size 0 0)
			(layers "F.Cu" "F.Mask" "F.Paste")
			(net "GND")
		)
	)
)
